(kicad_pcb
	(version 20260206)
	(generator "pcbnew")
	(generator_version "10.0")
	(general
		(thickness 1.6)
		(legacy_teardrops no)
	)
	(paper "A4")
	(title_block
		(title "Wiwynn_Tioga_Pass_MB.brd")
		(comment 1 "Tioga Pass / footprints 2762-2768 of 4770")
	)
	(layers
		(0 "F.Cu" signal "TOP")
		(4 "In1.Cu" signal "L2GND")
		(6 "In2.Cu" signal "L3")
		(8 "In3.Cu" signal "L4GND")
		(10 "In4.Cu" signal "L5")
		(12 "In5.Cu" signal "L6GND")
		(14 "In6.Cu" signal "L7VCC")
		(16 "In7.Cu" signal "L8VCC")
		(18 "In8.Cu" signal "L9GND")
		(20 "In9.Cu" signal "L10")
		(22 "In10.Cu" signal "L11GND")
		(24 "In11.Cu" signal "L12")
		(26 "In12.Cu" signal "L13GND")
		(2 "B.Cu" signal "BOTTOM")
		(9 "F.Adhes" user "F.Adhesive")
		(11 "B.Adhes" user "B.Adhesive")
		(13 "F.Paste" user "Package Geometry/Pastemask Top")
		(15 "B.Paste" user "Package Geometry/Pastemask Bottom")
		(5 "F.SilkS" user "Ref Des/Silkscreen Top")
		(7 "B.SilkS" user "Ref Des/Silkscreen Bottom")
		(1 "F.Mask" user "Board Geometry/Soldermask Top")
		(3 "B.Mask" user "Board Geometry/Soldermask Bottom")
		(17 "Dwgs.User" user "User.Drawings")
		(19 "Cmts.User" user "User.Comments")
		(21 "Eco1.User" user "User.Eco1")
		(23 "Eco2.User" user "User.Eco2")
		(25 "Edge.Cuts" user "Board Geometry/Outline")
		(27 "Margin" user)
		(31 "F.CrtYd" user "Package Geometry/Place Bound Top")
		(29 "B.CrtYd" user "Package Geometry/Place Bound Bottom")
		(35 "F.Fab" user "Ref Des/Assembly Top")
		(33 "B.Fab" user "Ref Des/Assembly Bottom")
	)
	(footprint ""
		(layer "B.Cu")
		(at 129.777998 -67.677538)
		(property "Reference" "R7P26"
			(at 0 0 0)
			(layer "B.SilkS")
			(hide yes)
			(effects
				(font
					(size 1.27 1.27)
				)
				(justify mirror)
			)
		)
		(property "Value" ""
			(at 0 0 0)
			(layer "B.Fab")
			(effects
				(font
					(size 1.27 1.27)
				)
				(justify mirror)
			)
		)
		(duplicate_pad_numbers_are_jumpers no)
		(fp_poly
			(pts
				(xy 0.2794 -0.1016) (xy -0.2794 -0.1016) (xy -0.2794 0.9906) (xy 0.2794 0.9906)
			)
			(stroke
				(width 0)
				(type default)
			)
			(fill no)
			(layer "B.CrtYd")
		)
		(fp_line
			(start -0.2794 -0.1016)
			(end 0.2794 -0.1016)
			(stroke
				(width 0.1)
				(type default)
			)
			(layer "B.Fab")
		)
		(fp_line
			(start -0.2794 0.9906)
			(end -0.2794 -0.1016)
			(stroke
				(width 0.1)
				(type default)
			)
			(layer "B.Fab")
		)
		(fp_line
			(start 0.2794 -0.1016)
			(end 0.2794 0.9906)
			(stroke
				(width 0.1)
				(type default)
			)
			(layer "B.Fab")
		)
		(fp_line
			(start 0.2794 0.9906)
			(end -0.2794 0.9906)
			(stroke
				(width 0.1)
				(type default)
			)
			(layer "B.Fab")
		)
		(pad "1" smd rect
			(at 0 0 180)
			(size 0.508 0.508)
			(layers "B.Cu" "B.Mask" "B.Paste")
			(net "H_PMSYNC_CLK_24M_CPU1")
		)
		(pad "2" smd rect
			(at 0 0.889 180)
			(size 0.508 0.508)
			(layers "B.Cu" "B.Mask" "B.Paste")
			(net "H_PMSYNC_CLK_24M")
		)
		(zone
			(layer "B.Cu")
			(hatch none 0.5)
			(connect_pads
				(clearance 0)
			)
			(min_thickness 0.25)
			(keepout
				(tracks allowed)
				(vias not_allowed)
				(pads allowed)
				(copperpour not_allowed)
				(footprints allowed)
			)
			(placement
				(enabled no)
				(sheetname "")
			)
			(fill
				(thermal_gap 0.5)
				(thermal_bridge_width 0.5)
				(island_removal_mode 0)
			)
			(polygon
				(pts
					(xy 130.031998 -67.423538) (xy 129.523998 -67.423538) (xy 129.523998 -67.042538) (xy 130.031998 -67.042538)
				)
			)
		)
		(zone
			(layer "B.Cu")
			(hatch none 0.5)
			(connect_pads
				(clearance 0)
			)
			(min_thickness 0.25)
			(keepout
				(tracks not_allowed)
				(vias allowed)
				(pads allowed)
				(copperpour not_allowed)
				(footprints allowed)
			)
			(placement
				(enabled no)
				(sheetname "")
			)
			(fill
				(thermal_gap 0.5)
				(thermal_bridge_width 0.5)
				(island_removal_mode 0)
			)
			(polygon
				(pts
					(xy 130.031998 -67.042538) (xy 129.523998 -67.042538) (xy 129.523998 -67.423538) (xy 130.031998 -67.423538)
				)
			)
		)
	)
	(footprint ""
		(layer "B.Cu")
		(at 383.73685 -111.05515 -90)
		(property "Reference" "C3N7"
			(at 0 0 90)
			(layer "B.SilkS")
			(hide yes)
			(effects
				(font
					(size 1.27 1.27)
				)
				(justify mirror)
			)
		)
		(property "Value" ""
			(at 0 0 90)
			(layer "B.Fab")
			(effects
				(font
					(size 1.27 1.27)
				)
				(justify mirror)
			)
		)
		(duplicate_pad_numbers_are_jumpers no)
		(fp_rect
			(start 0.2794 0.9144)
			(end -0.2794 -0.1143)
			(stroke
				(width 0)
				(type default)
			)
			(fill no)
			(layer "B.CrtYd")
		)
		(fp_line
			(start -0.2794 0.9144)
			(end 0.2794 0.9144)
			(stroke
				(width 0.1)
				(type default)
			)
			(layer "B.Fab")
		)
		(fp_line
			(start 0.2794 0.9144)
			(end 0.2794 -0.1143)
			(stroke
				(width 0.1)
				(type default)
			)
			(layer "B.Fab")
		)
		(fp_line
			(start -0.2794 -0.1143)
			(end -0.2794 0.9144)
			(stroke
				(width 0.1)
				(type default)
			)
			(layer "B.Fab")
		)
		(fp_line
			(start 0.2794 -0.1143)
			(end -0.2794 -0.1143)
			(stroke
				(width 0.1)
				(type default)
			)
			(layer "B.Fab")
		)
		(pad "1" smd custom
			(at 0 0 180)
			(size 0.10414 0.10414)
			(layers "B.Cu" "B.Mask" "B.Paste")
			(net "PVNN_PCH_STBY")
			(options
				(clearance outline)
				(anchor circle)
			)
			(primitives
				(gr_poly
					(pts
						(xy -0.20828 -0.08636) (xy -0.20828 0.08636) (xy -0.08636 0.20828) (xy 0.086614 0.20828) (xy 0.20828 0.086614)
						(xy 0.20828 -0.08636) (xy 0.08636 -0.20828) (xy -0.08636 -0.20828)
					)
					(width 0)
					(fill yes)
				)
			)
		)
		(pad "2" smd custom
			(at 0 0.8001 180)
			(size 0.10414 0.10414)
			(layers "B.Cu" "B.Mask" "B.Paste")
			(net "GND")
			(options
				(clearance outline)
				(anchor circle)
			)
			(primitives
				(gr_poly
					(pts
						(xy -0.20828 -0.08636) (xy -0.20828 0.08636) (xy -0.08636 0.20828) (xy 0.086614 0.20828) (xy 0.20828 0.086614)
						(xy 0.20828 -0.08636) (xy 0.08636 -0.20828) (xy -0.08636 -0.20828)
					)
					(width 0)
					(fill yes)
				)
			)
		)
		(zone
			(layer "B.Cu")
			(hatch none 0.5)
			(connect_pads
				(clearance 0)
			)
			(min_thickness 0.25)
			(keepout
				(tracks allowed)
				(vias not_allowed)
				(pads allowed)
				(copperpour not_allowed)
				(footprints allowed)
			)
			(placement
				(enabled no)
				(sheetname "")
			)
			(fill
				(thermal_gap 0.5)
				(thermal_bridge_width 0.5)
				(island_removal_mode 0)
			)
			(polygon
				(pts
					(xy 383.5273 -110.96752) (xy 383.1463 -110.96752) (xy 383.1463 -111.14278) (xy 383.5273 -111.143034)
				)
			)
		)
		(zone
			(layer "B.Cu")
			(hatch none 0.5)
			(connect_pads
				(clearance 0)
			)
			(min_thickness 0.25)
			(keepout
				(tracks not_allowed)
				(vias allowed)
				(pads allowed)
				(copperpour not_allowed)
				(footprints allowed)
			)
			(placement
				(enabled no)
				(sheetname "")
			)
			(fill
				(thermal_gap 0.5)
				(thermal_bridge_width 0.5)
				(island_removal_mode 0)
			)
			(polygon
				(pts
					(xy 383.5273 -110.96752) (xy 383.1463 -110.96752) (xy 383.1463 -111.14278) (xy 383.5273 -111.143034)
				)
			)
		)
	)
	(footprint ""
		(layer "B.Cu")
		(at 376.170952 -43.224958)
		(property "Reference" "R2T61"
			(at 0 0 0)
			(layer "B.SilkS")
			(hide yes)
			(effects
				(font
					(size 1.27 1.27)
				)
				(justify mirror)
			)
		)
		(property "Value" ""
			(at 0 0 0)
			(layer "B.Fab")
			(effects
				(font
					(size 1.27 1.27)
				)
				(justify mirror)
			)
		)
		(duplicate_pad_numbers_are_jumpers no)
		(fp_poly
			(pts
				(xy 0.2794 -0.1016) (xy -0.2794 -0.1016) (xy -0.2794 0.9906) (xy 0.2794 0.9906)
			)
			(stroke
				(width 0)
				(type default)
			)
			(fill no)
			(layer "B.CrtYd")
		)
		(fp_line
			(start -0.2794 -0.1016)
			(end 0.2794 -0.1016)
			(stroke
				(width 0.1)
				(type default)
			)
			(layer "B.Fab")
		)
		(fp_line
			(start -0.2794 0.9906)
			(end -0.2794 -0.1016)
			(stroke
				(width 0.1)
				(type default)
			)
			(layer "B.Fab")
		)
		(fp_line
			(start 0.2794 -0.1016)
			(end 0.2794 0.9906)
			(stroke
				(width 0.1)
				(type default)
			)
			(layer "B.Fab")
		)
		(fp_line
			(start 0.2794 0.9906)
			(end -0.2794 0.9906)
			(stroke
				(width 0.1)
				(type default)
			)
			(layer "B.Fab")
		)
		(pad "1" smd rect
			(at 0 0 180)
			(size 0.508 0.508)
			(layers "B.Cu" "B.Mask" "B.Paste")
			(net "H_CPU_ERR1_PCH_N")
		)
		(pad "2" smd rect
			(at 0 0.889 180)
			(size 0.508 0.508)
			(layers "B.Cu" "B.Mask" "B.Paste")
			(net "H_CPU_ERR1_GTL_R_N")
		)
		(zone
			(layer "B.Cu")
			(hatch none 0.5)
			(connect_pads
				(clearance 0)
			)
			(min_thickness 0.25)
			(keepout
				(tracks allowed)
				(vias not_allowed)
				(pads allowed)
				(copperpour not_allowed)
				(footprints allowed)
			)
			(placement
				(enabled no)
				(sheetname "")
			)
			(fill
				(thermal_gap 0.5)
				(thermal_bridge_width 0.5)
				(island_removal_mode 0)
			)
			(polygon
				(pts
					(xy 376.424952 -42.970958) (xy 375.916952 -42.970958) (xy 375.916952 -42.589958) (xy 376.424952 -42.589958)
				)
			)
		)
		(zone
			(layer "B.Cu")
			(hatch none 0.5)
			(connect_pads
				(clearance 0)
			)
			(min_thickness 0.25)
			(keepout
				(tracks not_allowed)
				(vias allowed)
				(pads allowed)
				(copperpour not_allowed)
				(footprints allowed)
			)
			(placement
				(enabled no)
				(sheetname "")
			)
			(fill
				(thermal_gap 0.5)
				(thermal_bridge_width 0.5)
				(island_removal_mode 0)
			)
			(polygon
				(pts
					(xy 376.424952 -42.589958) (xy 375.916952 -42.589958) (xy 375.916952 -42.970958) (xy 376.424952 -42.970958)
				)
			)
		)
	)
	(footprint ""
		(layer "B.Cu")
		(at 396.978886 -16.438372 180)
		(property "Reference" "R32W5"
			(at 0.8382 -0.67818 180)
			(unlocked yes)
			(layer "B.SilkS")
			(effects
				(font
					(size 0.4064 0.254)
					(thickness 0.1524)
				)
				(justify left mirror)
			)
		)
		(property "Value" ""
			(at 0 0 0)
			(layer "B.Fab")
			(effects
				(font
					(size 1.27 1.27)
				)
				(justify mirror)
			)
		)
		(duplicate_pad_numbers_are_jumpers no)
		(fp_poly
			(pts
				(xy 0.2794 -0.1016) (xy -0.2794 -0.1016) (xy -0.2794 0.9906) (xy 0.2794 0.9906)
			)
			(stroke
				(width 0)
				(type default)
			)
			(fill no)
			(layer "B.CrtYd")
		)
		(fp_line
			(start 0.2794 0.9906)
			(end -0.2794 0.9906)
			(stroke
				(width 0.1)
				(type default)
			)
			(layer "B.Fab")
		)
		(fp_line
			(start 0.2794 -0.1016)
			(end 0.2794 0.9906)
			(stroke
				(width 0.1)
				(type default)
			)
			(layer "B.Fab")
		)
		(fp_line
			(start -0.2794 0.9906)
			(end -0.2794 -0.1016)
			(stroke
				(width 0.1)
				(type default)
			)
			(layer "B.Fab")
		)
		(fp_line
			(start -0.2794 -0.1016)
			(end 0.2794 -0.1016)
			(stroke
				(width 0.1)
				(type default)
			)
			(layer "B.Fab")
		)
		(pad "1" smd rect
			(at 0 0)
			(size 0.508 0.508)
			(layers "B.Cu" "B.Mask" "B.Paste")
			(net "P1V8_M2")
		)
		(pad "2" smd rect
			(at 0 0.889)
			(size 0.508 0.508)
			(layers "B.Cu" "B.Mask" "B.Paste")
			(net "SMB_M2_SCL")
		)
		(zone
			(layer "B.Cu")
			(hatch none 0.5)
			(connect_pads
				(clearance 0)
			)
			(min_thickness 0.25)
			(keepout
				(tracks not_allowed)
				(vias allowed)
				(pads allowed)
				(copperpour not_allowed)
				(footprints allowed)
			)
			(placement
				(enabled no)
				(sheetname "")
			)
			(fill
				(thermal_gap 0.5)
				(thermal_bridge_width 0.5)
				(island_removal_mode 0)
			)
			(polygon
				(pts
					(xy 396.724886 -17.073372) (xy 397.232886 -17.073372) (xy 397.232886 -16.692372) (xy 396.724886 -16.692372)
				)
			)
		)
		(zone
			(layer "B.Cu")
			(hatch none 0.5)
			(connect_pads
				(clearance 0)
			)
			(min_thickness 0.25)
			(keepout
				(tracks allowed)
				(vias not_allowed)
				(pads allowed)
				(copperpour not_allowed)
				(footprints allowed)
			)
			(placement
				(enabled no)
				(sheetname "")
			)
			(fill
				(thermal_gap 0.5)
				(thermal_bridge_width 0.5)
				(island_removal_mode 0)
			)
			(polygon
				(pts
					(xy 396.724886 -16.692372) (xy 397.232886 -16.692372) (xy 397.232886 -17.073372) (xy 396.724886 -17.073372)
				)
			)
		)
	)
	(footprint ""
		(layer "B.Cu")
		(at 430.726088 -15.280894 -90)
		(property "Reference" "R9G32"
			(at 0 0 90)
			(layer "B.SilkS")
			(hide yes)
			(effects
				(font
					(size 1.27 1.27)
				)
				(justify mirror)
			)
		)
		(property "Value" ""
			(at 0 0 90)
			(layer "B.Fab")
			(effects
				(font
					(size 1.27 1.27)
				)
				(justify mirror)
			)
		)
		(duplicate_pad_numbers_are_jumpers no)
		(fp_poly
			(pts
				(xy 0.2794 -0.1016) (xy -0.2794 -0.1016) (xy -0.2794 0.9906) (xy 0.2794 0.9906)
			)
			(stroke
				(width 0)
				(type default)
			)
			(fill no)
			(layer "B.CrtYd")
		)
		(fp_line
			(start -0.2794 0.9906)
			(end -0.2794 -0.1016)
			(stroke
				(width 0.1)
				(type default)
			)
			(layer "B.Fab")
		)
		(fp_line
			(start 0.2794 0.9906)
			(end -0.2794 0.9906)
			(stroke
				(width 0.1)
				(type default)
			)
			(layer "B.Fab")
		)
		(fp_line
			(start -0.2794 -0.1016)
			(end 0.2794 -0.1016)
			(stroke
				(width 0.1)
				(type default)
			)
			(layer "B.Fab")
		)
		(fp_line
			(start 0.2794 -0.1016)
			(end 0.2794 0.9906)
			(stroke
				(width 0.1)
				(type default)
			)
			(layer "B.Fab")
		)
		(pad "1" smd rect
			(at 0 0 90)
			(size 0.508 0.508)
			(layers "B.Cu" "B.Mask" "B.Paste")
			(net "H_CPU1_GHJ_MEMHOT_LVT3_R_N")
		)
		(pad "2" smd rect
			(at 0 0.889 90)
			(size 0.508 0.508)
			(layers "B.Cu" "B.Mask" "B.Paste")
			(net "H_CPU1_MEMGHJ_MEMHOT_LVT3_K_N")
		)
		(zone
			(layer "B.Cu")
			(hatch none 0.5)
			(connect_pads
				(clearance 0)
			)
			(min_thickness 0.25)
			(keepout
				(tracks not_allowed)
				(vias allowed)
				(pads allowed)
				(copperpour not_allowed)
				(footprints allowed)
			)
			(placement
				(enabled no)
				(sheetname "")
			)
			(fill
				(thermal_gap 0.5)
				(thermal_bridge_width 0.5)
				(island_removal_mode 0)
			)
			(polygon
				(pts
					(xy 430.091088 -15.026894) (xy 430.091088 -15.534894) (xy 430.472088 -15.534894) (xy 430.472088 -15.026894)
				)
			)
		)
		(zone
			(layer "B.Cu")
			(hatch none 0.5)
			(connect_pads
				(clearance 0)
			)
			(min_thickness 0.25)
			(keepout
				(tracks allowed)
				(vias not_allowed)
				(pads allowed)
				(copperpour not_allowed)
				(footprints allowed)
			)
			(placement
				(enabled no)
				(sheetname "")
			)
			(fill
				(thermal_gap 0.5)
				(thermal_bridge_width 0.5)
				(island_removal_mode 0)
			)
			(polygon
				(pts
					(xy 430.472088 -15.026894) (xy 430.472088 -15.534894) (xy 430.091088 -15.534894) (xy 430.091088 -15.026894)
				)
			)
		)
	)
	(footprint ""
		(layer "B.Cu")
		(at 430.85512 -141.939518 90)
		(property "Reference" "C2L52"
			(at 0 0 90)
			(layer "B.SilkS")
			(hide yes)
			(effects
				(font
					(size 1.27 1.27)
				)
				(justify mirror)
			)
		)
		(property "Value" ""
			(at 0 0 90)
			(layer "B.Fab")
			(effects
				(font
					(size 1.27 1.27)
				)
				(justify mirror)
			)
		)
		(duplicate_pad_numbers_are_jumpers no)
		(fp_poly
			(pts
				(xy -0.3048 -0.1016) (xy -0.3048 0.9906) (xy 0.3048 0.9906) (xy 0.3048 -0.1016)
			)
			(stroke
				(width 0)
				(type default)
			)
			(fill no)
			(layer "B.CrtYd")
		)
		(fp_line
			(start 0.3048 -0.1016)
			(end 0.3048 0.9906)
			(stroke
				(width 0.1)
				(type default)
			)
			(layer "B.Fab")
		)
		(fp_line
			(start -0.3048 -0.1016)
			(end 0.3048 -0.1016)
			(stroke
				(width 0.1)
				(type default)
			)
			(layer "B.Fab")
		)
		(fp_line
			(start 0.3048 0.9906)
			(end -0.3048 0.9906)
			(stroke
				(width 0.1)
				(type default)
			)
			(layer "B.Fab")
		)
		(fp_line
			(start -0.3048 0.9906)
			(end -0.3048 -0.1016)
			(stroke
				(width 0.1)
				(type default)
			)
			(layer "B.Fab")
		)
		(pad "1" smd rect
			(at 0 0 270)
			(size 0.508 0.508)
			(layers "B.Cu" "B.Mask" "B.Paste")
			(net "SATA6G_S1_TX_C_DP")
		)
		(pad "2" smd rect
			(at 0 0.889 270)
			(size 0.508 0.508)
			(layers "B.Cu" "B.Mask" "B.Paste")
			(net "SATA6G_S1_TX_DP")
		)
		(zone
			(layer "B.Cu")
			(hatch none 0.5)
			(connect_pads
				(clearance 0)
			)
			(min_thickness 0.25)
			(keepout
				(tracks allowed)
				(vias not_allowed)
				(pads allowed)
				(copperpour not_allowed)
				(footprints allowed)
			)
			(placement
				(enabled no)
				(sheetname "")
			)
			(fill
				(thermal_gap 0.5)
				(thermal_bridge_width 0.5)
				(island_removal_mode 0)
			)
			(polygon
				(pts
					(xy 431.10912 -142.193518) (xy 431.10912 -141.685518) (xy 431.49012 -141.685518) (xy 431.49012 -142.193518)
				)
			)
		)
		(zone
			(layer "B.Cu")
			(hatch none 0.5)
			(connect_pads
				(clearance 0)
			)
			(min_thickness 0.25)
			(keepout
				(tracks not_allowed)
				(vias allowed)
				(pads allowed)
				(copperpour not_allowed)
				(footprints allowed)
			)
			(placement
				(enabled no)
				(sheetname "")
			)
			(fill
				(thermal_gap 0.5)
				(thermal_bridge_width 0.5)
				(island_removal_mode 0)
			)
			(polygon
				(pts
					(xy 431.49012 -142.193518) (xy 431.49012 -141.685518) (xy 431.10912 -141.685518) (xy 431.10912 -142.193518)
				)
			)
		)
	)
	(footprint ""
		(layer "B.Cu")
		(at 468.2744 -41.5798)
		(property "Reference" "C1T7"
			(at 0 0 0)
			(layer "B.SilkS")
			(hide yes)
			(effects
				(font
					(size 1.27 1.27)
				)
				(justify mirror)
			)
		)
		(property "Value" ""
			(at 0 0 0)
			(layer "B.Fab")
			(effects
				(font
					(size 1.27 1.27)
				)
				(justify mirror)
			)
		)
		(duplicate_pad_numbers_are_jumpers no)
		(fp_poly
			(pts
				(xy 0.4953 -0.2032) (xy -0.4953 -0.2032) (xy -0.4953 1.6002) (xy 0.4953 1.6002)
			)
			(stroke
				(width 0)
				(type default)
			)
			(fill no)
			(layer "B.CrtYd")
		)
		(fp_line
			(start -0.4953 -0.2032)
			(end -0.4953 1.6002)
			(stroke
				(width 0.1)
				(type default)
			)
			(layer "B.Fab")
		)
		(fp_line
			(start -0.4953 1.6002)
			(end 0.4953 1.6002)
			(stroke
				(width 0.1)
				(type default)
			)
			(layer "B.Fab")
		)
		(fp_line
			(start 0.4953 -0.2032)
			(end -0.4953 -0.2032)
			(stroke
				(width 0.1)
				(type default)
			)
			(layer "B.Fab")
		)
		(fp_line
			(start 0.4953 1.6002)
			(end 0.4953 -0.2032)
			(stroke
				(width 0.1)
				(type default)
			)
			(layer "B.Fab")
		)
		(pad "1" smd rect
			(at 0 0 180)
			(size 0.762 0.889)
			(layers "B.Cu" "B.Mask" "B.Paste")
			(net "P3V3_STBY")
		)
		(pad "2" smd rect
			(at 0 1.397 180)
			(size 0.762 0.889)
			(layers "B.Cu" "B.Mask" "B.Paste")
			(net "GND")
		)
		(zone
			(layer "B.Cu")
			(hatch none 0.5)
			(connect_pads
				(clearance 0)
			)
			(min_thickness 0.25)
			(keepout
				(tracks not_allowed)
				(vias allowed)
				(pads allowed)
				(copperpour not_allowed)
				(footprints allowed)
			)
			(placement
				(enabled no)
				(sheetname "")
			)
			(fill
				(thermal_gap 0.5)
				(thermal_bridge_width 0.5)
				(island_removal_mode 0)
			)
			(polygon
				(pts
					(xy 468.6554 -41.1353) (xy 467.8934 -41.1353) (xy 467.8934 -40.6273) (xy 468.6554 -40.6273)
				)
			)
		)
	)
)
